(kicad_pcb
	(version 20260206)
	(generator "pcbnew")
	(generator_version "10.0")
	(general
		(thickness 1.6)
		(legacy_teardrops no)
	)
	(paper "A4")
	(title_block
		(title "pdpb — Lightning_PDPB_BRD.brd")
		(comment 1 "Lightning (Wiwynn / Facebook NVMe JBOF) / footprints 14-20 of 1140")
	)
	(layers
		(0 "F.Cu" signal "TOP")
		(4 "In1.Cu" signal "L2GND")
		(6 "In2.Cu" signal "L3")
		(8 "In3.Cu" signal "L4VCC")
		(10 "In4.Cu" signal "L5VCC")
		(12 "In5.Cu" signal "L6")
		(14 "In6.Cu" signal "L7GND")
		(2 "B.Cu" signal "BOTTOM")
		(9 "F.Adhes" user "F.Adhesive")
		(11 "B.Adhes" user "B.Adhesive")
		(13 "F.Paste" user "Package Geometry/Pastemask Top")
		(15 "B.Paste" user "Package Geometry/Pastemask Bottom")
		(5 "F.SilkS" user "Ref Des/Silkscreen Top")
		(7 "B.SilkS" user "Ref Des/Silkscreen Bottom")
		(1 "F.Mask" user "Board Geometry/Soldermask Top")
		(3 "B.Mask" user "Board Geometry/Soldermask Bottom")
		(17 "Dwgs.User" user "User.Drawings")
		(19 "Cmts.User" user "User.Comments")
		(21 "Eco1.User" user "User.Eco1")
		(23 "Eco2.User" user "User.Eco2")
		(25 "Edge.Cuts" user "Board Geometry/Outline")
		(27 "Margin" user)
		(31 "F.CrtYd" user "Package Geometry/Place Bound Top")
		(29 "B.CrtYd" user "Package Geometry/Place Bound Bottom")
		(35 "F.Fab" user "Ref Des/Assembly Top")
		(33 "B.Fab" user "Ref Des/Assembly Bottom")
	)
	(footprint ""
		(layer "F.Cu")
		(at 213.3981 -403.5171 180)
		(property "Reference" "R9786"
			(at 0 0 180)
			(layer "F.SilkS")
			(hide yes)
			(effects
				(font
					(size 1.27 1.27)
				)
			)
		)
		(property "Value" "47KR2J-2-GP"
			(at 0.064008 -3.993896 180)
			(unlocked yes)
			(layer "F.Fab")
			(hide yes)
			(effects
				(font
					(size 1.016 1.016)
					(thickness 0.1524)
				)
			)
		)
		(property "Device Type" "R402H16"
			(at 0.064008 -5.517896 180)
			(unlocked yes)
			(layer "F.Fab")
			(hide yes)
			(effects
				(font
					(size 1.016 1.016)
					(thickness 0.1524)
				)
			)
		)
		(duplicate_pad_numbers_are_jumpers no)
		(fp_line
			(start 0.508 -0.9398)
			(end -0.508 -0.9398)
			(stroke
				(width 0.1524)
				(type default)
			)
			(layer "F.SilkS")
		)
		(fp_line
			(start -0.508 -0.9398)
			(end -0.508 0.9398)
			(stroke
				(width 0.1524)
				(type default)
			)
			(layer "F.SilkS")
		)
		(fp_rect
			(start -0.508 0.9398)
			(end 0.508 -0.9398)
			(stroke
				(width 0)
				(type default)
			)
			(fill no)
			(layer "F.CrtYd")
		)
		(fp_rect
			(start -0.508 0.9398)
			(end 0.508 -0.9398)
			(stroke
				(width 0)
				(type default)
			)
			(fill no)
			(layer "F.Fab")
		)
		(pad "1" smd custom
			(at 0 -0.4445 180)
			(size 0.1397 0.1397)
			(layers "F.Cu" "F.Mask" "F.Paste")
			(net "P12V")
			(options
				(clearance outline)
				(anchor circle)
			)
			(primitives
				(gr_poly
					(pts
						(arc
							(start -0.1778 -0.2794)
							(mid -0.249642 -0.249642)
							(end -0.2794 -0.1778)
						)
						(arc
							(start -0.2794 0.1778)
							(mid -0.249642 0.249642)
							(end -0.1778 0.2794)
						)
						(arc
							(start 0.1778 0.2794)
							(mid 0.249642 0.249642)
							(end 0.2794 0.1778)
						)
						(arc
							(start 0.2794 -0.1778)
							(mid 0.249642 -0.249642)
							(end 0.1778 -0.2794)
						)
					)
					(width 0)
					(fill yes)
				)
			)
		)
		(pad "2" smd custom
			(at 0 0.4445 180)
			(size 0.1397 0.1397)
			(layers "F.Cu" "F.Mask" "F.Paste")
			(net "P12V_MOST1_GATE")
			(options
				(clearance outline)
				(anchor circle)
			)
			(primitives
				(gr_poly
					(pts
						(arc
							(start -0.1778 -0.2794)
							(mid -0.249642 -0.249642)
							(end -0.2794 -0.1778)
						)
						(arc
							(start -0.2794 0.1778)
							(mid -0.249642 0.249642)
							(end -0.1778 0.2794)
						)
						(arc
							(start 0.1778 0.2794)
							(mid 0.249642 0.249642)
							(end 0.2794 0.1778)
						)
						(arc
							(start 0.2794 -0.1778)
							(mid 0.249642 -0.249642)
							(end 0.1778 -0.2794)
						)
					)
					(width 0)
					(fill yes)
				)
			)
		)
	)
	(footprint ""
		(layer "F.Cu")
		(at 24.638 -395.351 -90)
		(property "Reference" "R144"
			(at 0 0 270)
			(layer "F.SilkS")
			(hide yes)
			(effects
				(font
					(size 1.27 1.27)
				)
			)
		)
		(property "Value" "4K7R2J-2-GP"
			(at 0.064008 -3.993896 270)
			(unlocked yes)
			(layer "F.Fab")
			(hide yes)
			(effects
				(font
					(size 1.016 1.016)
					(thickness 0.1524)
				)
			)
		)
		(property "Device Type" "R402H16"
			(at 0.064008 -5.517896 270)
			(unlocked yes)
			(layer "F.Fab")
			(hide yes)
			(effects
				(font
					(size 1.016 1.016)
					(thickness 0.1524)
				)
			)
		)
		(duplicate_pad_numbers_are_jumpers no)
		(fp_line
			(start -0.508 -0.9398)
			(end -0.508 0.9398)
			(stroke
				(width 0.1524)
				(type default)
			)
			(layer "F.SilkS")
		)
		(fp_line
			(start 0.508 -0.9398)
			(end -0.508 -0.9398)
			(stroke
				(width 0.1524)
				(type default)
			)
			(layer "F.SilkS")
		)
		(fp_rect
			(start -0.508 0.9398)
			(end 0.508 -0.9398)
			(stroke
				(width 0)
				(type default)
			)
			(fill no)
			(layer "F.CrtYd")
		)
		(fp_rect
			(start -0.508 0.9398)
			(end 0.508 -0.9398)
			(stroke
				(width 0)
				(type default)
			)
			(fill no)
			(layer "F.Fab")
		)
		(pad "1" smd custom
			(at 0 -0.4445 270)
			(size 0.1397 0.1397)
			(layers "F.Cu" "F.Mask" "F.Paste")
			(net "P12V")
			(options
				(clearance outline)
				(anchor circle)
			)
			(primitives
				(gr_poly
					(pts
						(arc
							(start -0.1778 -0.2794)
							(mid -0.249642 -0.249642)
							(end -0.2794 -0.1778)
						)
						(arc
							(start -0.2794 0.1778)
							(mid -0.249642 0.249642)
							(end -0.1778 0.2794)
						)
						(arc
							(start 0.1778 0.2794)
							(mid 0.249642 0.249642)
							(end 0.2794 0.1778)
						)
						(arc
							(start 0.2794 -0.1778)
							(mid 0.249642 -0.249642)
							(end 0.1778 -0.2794)
						)
					)
					(width 0)
					(fill yes)
				)
			)
		)
		(pad "2" smd custom
			(at 0 0.4445 270)
			(size 0.1397 0.1397)
			(layers "F.Cu" "F.Mask" "F.Paste")
			(net "SW_SSD6_R")
			(options
				(clearance outline)
				(anchor circle)
			)
			(primitives
				(gr_poly
					(pts
						(arc
							(start -0.1778 -0.2794)
							(mid -0.249642 -0.249642)
							(end -0.2794 -0.1778)
						)
						(arc
							(start -0.2794 0.1778)
							(mid -0.249642 0.249642)
							(end -0.1778 0.2794)
						)
						(arc
							(start 0.1778 0.2794)
							(mid 0.249642 0.249642)
							(end 0.2794 0.1778)
						)
						(arc
							(start 0.2794 -0.1778)
							(mid 0.249642 -0.249642)
							(end 0.1778 -0.2794)
						)
					)
					(width 0)
					(fill yes)
				)
			)
		)
	)
	(footprint ""
		(layer "F.Cu")
		(at 32.131 -381.508 -90)
		(property "Reference" "C343"
			(at 0 0 270)
			(layer "F.SilkS")
			(hide yes)
			(effects
				(font
					(size 1.27 1.27)
				)
			)
		)
		(property "Value" "SCD1U16V2KX-3GP"
			(at 1.1811 -2.7051 270)
			(unlocked yes)
			(layer "F.Fab")
			(hide yes)
			(effects
				(font
					(size 1.016 1.016)
					(thickness 0.1524)
				)
			)
		)
		(property "Device Type" "C402H22"
			(at 1.1811 -4.2291 270)
			(unlocked yes)
			(layer "F.Fab")
			(hide yes)
			(effects
				(font
					(size 1.016 1.016)
					(thickness 0.1524)
				)
			)
		)
		(duplicate_pad_numbers_are_jumpers no)
		(fp_rect
			(start -0.4318 0.9525)
			(end 0.4318 -0.9525)
			(stroke
				(width 0)
				(type default)
			)
			(fill no)
			(layer "F.CrtYd")
		)
		(fp_rect
			(start -0.4318 0.9525)
			(end 0.4318 -0.9525)
			(stroke
				(width 0)
				(type default)
			)
			(fill no)
			(layer "F.Fab")
		)
		(pad "1" smd custom
			(at 0 -0.4445 270)
			(size 0.1524 0.1524)
			(layers "F.Cu" "F.Mask" "F.Paste")
			(net "P3V3")
			(options
				(clearance outline)
				(anchor circle)
			)
			(primitives
				(gr_poly
					(pts
						(arc
							(start 0.3048 -0.2032)
							(mid 0.275042 -0.275042)
							(end 0.2032 -0.3048)
						)
						(arc
							(start -0.2032 -0.3048)
							(mid -0.275042 -0.275042)
							(end -0.3048 -0.2032)
						)
						(arc
							(start -0.3048 0.2032)
							(mid -0.275042 0.275042)
							(end -0.2032 0.3048)
						)
						(arc
							(start 0.2032 0.3048)
							(mid 0.275042 0.275042)
							(end 0.3048 0.2032)
						)
					)
					(width 0)
					(fill yes)
				)
			)
		)
		(pad "2" smd custom
			(at 0 0.4445 270)
			(size 0.1524 0.1524)
			(layers "F.Cu" "F.Mask" "F.Paste")
			(net "GND")
			(options
				(clearance outline)
				(anchor circle)
			)
			(primitives
				(gr_poly
					(pts
						(arc
							(start 0.3048 -0.2032)
							(mid 0.275042 -0.275042)
							(end 0.2032 -0.3048)
						)
						(arc
							(start -0.2032 -0.3048)
							(mid -0.275042 -0.275042)
							(end -0.3048 -0.2032)
						)
						(arc
							(start -0.3048 0.2032)
							(mid -0.275042 0.275042)
							(end -0.2032 0.3048)
						)
						(arc
							(start 0.2032 0.3048)
							(mid 0.275042 0.275042)
							(end 0.3048 0.2032)
						)
					)
					(width 0)
					(fill yes)
				)
			)
		)
	)
	(footprint ""
		(layer "F.Cu")
		(at 37.1856 -108.3564 90)
		(property "Reference" "R151"
			(at 0 0 90)
			(layer "F.SilkS")
			(hide yes)
			(effects
				(font
					(size 1.27 1.27)
				)
			)
		)
		(property "Value" "4K7R2J-2-GP"
			(at 0.064008 -3.993896 90)
			(unlocked yes)
			(layer "F.Fab")
			(hide yes)
			(effects
				(font
					(size 1.016 1.016)
					(thickness 0.1524)
				)
			)
		)
		(property "Device Type" "R402H16"
			(at 0.064008 -5.517896 90)
			(unlocked yes)
			(layer "F.Fab")
			(hide yes)
			(effects
				(font
					(size 1.016 1.016)
					(thickness 0.1524)
				)
			)
		)
		(duplicate_pad_numbers_are_jumpers no)
		(fp_line
			(start 0.508 -0.9398)
			(end -0.508 -0.9398)
			(stroke
				(width 0.1524)
				(type default)
			)
			(layer "F.SilkS")
		)
		(fp_line
			(start -0.508 -0.9398)
			(end -0.508 0.9398)
			(stroke
				(width 0.1524)
				(type default)
			)
			(layer "F.SilkS")
		)
		(fp_rect
			(start -0.508 0.9398)
			(end 0.508 -0.9398)
			(stroke
				(width 0)
				(type default)
			)
			(fill no)
			(layer "F.CrtYd")
		)
		(fp_rect
			(start -0.508 0.9398)
			(end 0.508 -0.9398)
			(stroke
				(width 0)
				(type default)
			)
			(fill no)
			(layer "F.Fab")
		)
		(pad "1" smd custom
			(at 0 -0.4445 90)
			(size 0.1397 0.1397)
			(layers "F.Cu" "F.Mask" "F.Paste")
			(net "P12V")
			(options
				(clearance outline)
				(anchor circle)
			)
			(primitives
				(gr_poly
					(pts
						(arc
							(start -0.1778 -0.2794)
							(mid -0.249642 -0.249642)
							(end -0.2794 -0.1778)
						)
						(arc
							(start -0.2794 0.1778)
							(mid -0.249642 0.249642)
							(end -0.1778 0.2794)
						)
						(arc
							(start 0.1778 0.2794)
							(mid 0.249642 0.249642)
							(end 0.2794 0.1778)
						)
						(arc
							(start 0.2794 -0.1778)
							(mid 0.249642 -0.249642)
							(end 0.1778 -0.2794)
						)
					)
					(width 0)
					(fill yes)
				)
			)
		)
		(pad "2" smd custom
			(at 0 0.4445 90)
			(size 0.1397 0.1397)
			(layers "F.Cu" "F.Mask" "F.Paste")
			(net "SW_SSD13_R")
			(options
				(clearance outline)
				(anchor circle)
			)
			(primitives
				(gr_poly
					(pts
						(arc
							(start -0.1778 -0.2794)
							(mid -0.249642 -0.249642)
							(end -0.2794 -0.1778)
						)
						(arc
							(start -0.2794 0.1778)
							(mid -0.249642 0.249642)
							(end -0.1778 0.2794)
						)
						(arc
							(start 0.1778 0.2794)
							(mid 0.249642 0.249642)
							(end 0.2794 0.1778)
						)
						(arc
							(start 0.2794 -0.1778)
							(mid 0.249642 -0.249642)
							(end 0.1778 -0.2794)
						)
					)
					(width 0)
					(fill yes)
				)
			)
		)
	)
	(footprint ""
		(layer "F.Cu")
		(at 243.586 -412.5976)
		(property "Reference" "PC1289"
			(at 0 0 0)
			(layer "F.SilkS")
			(hide yes)
			(effects
				(font
					(size 1.27 1.27)
				)
			)
		)
		(property "Value" "SCD1U25V3KX-GP"
			(at 0 -2.8194 0)
			(unlocked yes)
			(layer "F.Fab")
			(hide yes)
			(effects
				(font
					(size 1.016 1.016)
					(thickness 0.1524)
				)
			)
		)
		(property "Device Type" "C603H36"
			(at 0 -4.3434 0)
			(unlocked yes)
			(layer "F.Fab")
			(hide yes)
			(effects
				(font
					(size 1.016 1.016)
					(thickness 0.1524)
				)
			)
		)
		(duplicate_pad_numbers_are_jumpers no)
		(fp_line
			(start 0.508 0)
			(end -0.508 0)
			(stroke
				(width 0.2032)
				(type default)
			)
			(layer "F.SilkS")
		)
		(fp_rect
			(start -0.5842 1.3335)
			(end 0.5842 -1.3335)
			(stroke
				(width 0)
				(type default)
			)
			(fill no)
			(layer "F.CrtYd")
		)
		(fp_rect
			(start -0.5842 1.3335)
			(end 0.5842 -1.3335)
			(stroke
				(width 0)
				(type default)
			)
			(fill no)
			(layer "F.Fab")
		)
		(pad "1" smd custom
			(at 0 -0.762)
			(size 0.2159 0.2159)
			(layers "F.Cu" "F.Mask" "F.Paste")
			(net "P3V3")
			(options
				(clearance outline)
				(anchor circle)
			)
			(primitives
				(gr_poly
					(pts
						(arc
							(start -0.3302 -0.4318)
							(mid -0.402042 -0.402042)
							(end -0.4318 -0.3302)
						)
						(arc
							(start -0.4318 0.3302)
							(mid -0.402042 0.402042)
							(end -0.3302 0.4318)
						)
						(arc
							(start 0.3302 0.4318)
							(mid 0.402042 0.402042)
							(end 0.4318 0.3302)
						)
						(arc
							(start 0.4318 -0.3302)
							(mid 0.402042 -0.402042)
							(end 0.3302 -0.4318)
						)
					)
					(width 0)
					(fill yes)
				)
			)
		)
		(pad "2" smd custom
			(at 0 0.762)
			(size 0.2159 0.2159)
			(layers "F.Cu" "F.Mask" "F.Paste")
			(net "GND")
			(options
				(clearance outline)
				(anchor circle)
			)
			(primitives
				(gr_poly
					(pts
						(arc
							(start -0.3302 -0.4318)
							(mid -0.402042 -0.402042)
							(end -0.4318 -0.3302)
						)
						(arc
							(start -0.4318 0.3302)
							(mid -0.402042 0.402042)
							(end -0.3302 0.4318)
						)
						(arc
							(start 0.3302 0.4318)
							(mid 0.402042 0.402042)
							(end 0.4318 0.3302)
						)
						(arc
							(start 0.4318 -0.3302)
							(mid 0.402042 -0.402042)
							(end 0.3302 -0.4318)
						)
					)
					(width 0)
					(fill yes)
				)
			)
		)
	)
	(footprint ""
		(layer "F.Cu")
		(at 24.003 -156.337 -90)
		(property "Reference" "R9421"
			(at 0 0 270)
			(layer "F.SilkS")
			(hide yes)
			(effects
				(font
					(size 1.27 1.27)
				)
			)
		)
		(property "Value" "330R2F-GP"
			(at 0.064008 -3.993896 270)
			(unlocked yes)
			(layer "F.Fab")
			(hide yes)
			(effects
				(font
					(size 1.016 1.016)
					(thickness 0.1524)
				)
			)
		)
		(property "Device Type" "R402H16"
			(at 0.064008 -5.517896 270)
			(unlocked yes)
			(layer "F.Fab")
			(hide yes)
			(effects
				(font
					(size 1.016 1.016)
					(thickness 0.1524)
				)
			)
		)
		(duplicate_pad_numbers_are_jumpers no)
		(fp_line
			(start -0.508 -0.9398)
			(end -0.508 0.9398)
			(stroke
				(width 0.1524)
				(type default)
			)
			(layer "F.SilkS")
		)
		(fp_line
			(start 0.508 -0.9398)
			(end -0.508 -0.9398)
			(stroke
				(width 0.1524)
				(type default)
			)
			(layer "F.SilkS")
		)
		(fp_rect
			(start -0.508 0.9398)
			(end 0.508 -0.9398)
			(stroke
				(width 0)
				(type default)
			)
			(fill no)
			(layer "F.CrtYd")
		)
		(fp_rect
			(start -0.508 0.9398)
			(end 0.508 -0.9398)
			(stroke
				(width 0)
				(type default)
			)
			(fill no)
			(layer "F.Fab")
		)
		(pad "1" smd custom
			(at 0 -0.4445 270)
			(size 0.1397 0.1397)
			(layers "F.Cu" "F.Mask" "F.Paste")
			(net "P3V3")
			(options
				(clearance outline)
				(anchor circle)
			)
			(primitives
				(gr_poly
					(pts
						(arc
							(start -0.1778 -0.2794)
							(mid -0.249642 -0.249642)
							(end -0.2794 -0.1778)
						)
						(arc
							(start -0.2794 0.1778)
							(mid -0.249642 0.249642)
							(end -0.1778 0.2794)
						)
						(arc
							(start 0.1778 0.2794)
							(mid 0.249642 0.249642)
							(end 0.2794 0.1778)
						)
						(arc
							(start 0.2794 -0.1778)
							(mid 0.249642 -0.249642)
							(end 0.1778 -0.2794)
						)
					)
					(width 0)
					(fill yes)
				)
			)
		)
		(pad "2" smd custom
			(at 0 0.4445 270)
			(size 0.1397 0.1397)
			(layers "F.Cu" "F.Mask" "F.Paste")
			(net "DRV_ATTN_13")
			(options
				(clearance outline)
				(anchor circle)
			)
			(primitives
				(gr_poly
					(pts
						(arc
							(start -0.1778 -0.2794)
							(mid -0.249642 -0.249642)
							(end -0.2794 -0.1778)
						)
						(arc
							(start -0.2794 0.1778)
							(mid -0.249642 0.249642)
							(end -0.1778 0.2794)
						)
						(arc
							(start 0.1778 0.2794)
							(mid 0.249642 0.249642)
							(end 0.2794 0.1778)
						)
						(arc
							(start 0.2794 -0.1778)
							(mid 0.249642 -0.249642)
							(end 0.1778 -0.2794)
						)
					)
					(width 0)
					(fill yes)
				)
			)
		)
	)
	(footprint ""
		(layer "F.Cu")
		(at 234.315 -430.53 -90)
		(property "Reference" "PR9085"
			(at 0 0 270)
			(layer "F.SilkS")
			(hide yes)
			(effects
				(font
					(size 1.27 1.27)
				)
			)
		)
		(property "Value" "10R3F-GP"
			(at -0.0254 -2.5146 270)
			(unlocked yes)
			(layer "F.Fab")
			(hide yes)
			(effects
				(font
					(size 1.016 1.016)
					(thickness 0.1524)
				)
			)
		)
		(property "Device Type" "R603H22"
			(at -0.0254 -4.0386 270)
			(unlocked yes)
			(layer "F.Fab")
			(hide yes)
			(effects
				(font
					(size 1.016 1.016)
					(thickness 0.1524)
				)
			)
		)
		(duplicate_pad_numbers_are_jumpers no)
		(fp_line
			(start -0.4826 0)
			(end -0.2032 0)
			(stroke
				(width 0.2032)
				(type default)
			)
			(layer "F.SilkS")
		)
		(fp_line
			(start 0.2032 0)
			(end 0.4826 0)
			(stroke
				(width 0.2032)
				(type default)
			)
			(layer "F.SilkS")
		)
		(fp_rect
			(start -0.5842 1.3335)
			(end 0.5842 -1.3335)
			(stroke
				(width 0)
				(type default)
			)
			(fill no)
			(layer "F.CrtYd")
		)
		(fp_rect
			(start -0.5842 1.3335)
			(end 0.5842 -1.3335)
			(stroke
				(width 0)
				(type default)
			)
			(fill no)
			(layer "F.Fab")
		)
		(pad "1" smd custom
			(at 0 -0.762 270)
			(size 0.2159 0.2159)
			(layers "F.Cu" "F.Mask" "F.Paste")
			(net "P3V3_CC")
			(options
				(clearance outline)
				(anchor circle)
			)
			(primitives
				(gr_poly
					(pts
						(arc
							(start -0.3302 -0.4318)
							(mid -0.402042 -0.402042)
							(end -0.4318 -0.3302)
						)
						(arc
							(start -0.4318 0.3302)
							(mid -0.402042 0.402042)
							(end -0.3302 0.4318)
						)
						(arc
							(start 0.3302 0.4318)
							(mid 0.402042 0.402042)
							(end 0.4318 0.3302)
						)
						(arc
							(start 0.4318 -0.3302)
							(mid 0.402042 -0.402042)
							(end 0.3302 -0.4318)
						)
					)
					(width 0)
					(fill yes)
				)
			)
		)
		(pad "2" smd custom
			(at 0 0.762 270)
			(size 0.2159 0.2159)
			(layers "F.Cu" "F.Mask" "F.Paste")
			(net "P3V3_CC_R")
			(options
				(clearance outline)
				(anchor circle)
			)
			(primitives
				(gr_poly
					(pts
						(arc
							(start -0.3302 -0.4318)
							(mid -0.402042 -0.402042)
							(end -0.4318 -0.3302)
						)
						(arc
							(start -0.4318 0.3302)
							(mid -0.402042 0.402042)
							(end -0.3302 0.4318)
						)
						(arc
							(start 0.3302 0.4318)
							(mid 0.402042 0.402042)
							(end 0.4318 0.3302)
						)
						(arc
							(start 0.4318 -0.3302)
							(mid 0.402042 -0.402042)
							(end 0.3302 -0.4318)
						)
					)
					(width 0)
					(fill yes)
				)
			)
		)
	)
)
